(kicad_pcb
	(version 20260206)
	(generator "pcbnew")
	(generator_version "10.0")
	(general
		(thickness 1.6)
		(legacy_teardrops no)
	)
	(paper "A4")
	(title_block
		(title "Bryce Canyon_R.DPB_16317-1_OCP.brd")
		(comment 1 "Bryce Canyon / footprint 518 of 2099 (DPB1), pads 74-150 of 150")
	)
	(layers
		(0 "F.Cu" signal "TOP")
		(4 "In1.Cu" signal "L2GND")
		(6 "In2.Cu" signal "L3")
		(8 "In3.Cu" signal "L4VCC")
		(10 "In4.Cu" signal "L5VCC")
		(12 "In5.Cu" signal "L6")
		(14 "In6.Cu" signal "L7GND")
		(2 "B.Cu" signal "BOTTOM")
		(9 "F.Adhes" user "F.Adhesive")
		(11 "B.Adhes" user "B.Adhesive")
		(13 "F.Paste" user "Package Geometry/Pastemask Top")
		(15 "B.Paste" user "Package Geometry/Pastemask Bottom")
		(5 "F.SilkS" user "Ref Des/Silkscreen Top")
		(7 "B.SilkS" user "Ref Des/Silkscreen Bottom")
		(1 "F.Mask" user "Board Geometry/Soldermask Top")
		(3 "B.Mask" user "Board Geometry/Soldermask Bottom")
		(17 "Dwgs.User" user "User.Drawings")
		(19 "Cmts.User" user "User.Comments")
		(21 "Eco1.User" user "User.Eco1")
		(23 "Eco2.User" user "User.Eco2")
		(25 "Edge.Cuts" user "Board Geometry/Outline")
		(27 "Margin" user)
		(31 "F.CrtYd" user "Package Geometry/Place Bound Top")
		(29 "B.CrtYd" user "Package Geometry/Place Bound Bottom")
		(35 "F.Fab" user "Ref Des/Assembly Top")
		(33 "B.Fab" user "Ref Des/Assembly Bottom")
	)
	(footprint ""
		(layer "F.Cu")
		(at 210.000088 -66.799968)
		(property "Reference" "DPB1"
			(at 0 0 0)
			(layer "F.SilkS")
			(hide yes)
			(effects
				(font
					(size 1.27 1.27)
				)
			)
		)
		(property "Value" "AMP-CONN150-13R-7-GP"
			(at -11.7475 -21.488654 0)
			(unlocked yes)
			(layer "F.Fab")
			(hide yes)
			(effects
				(font
					(size 1.016 1.016)
					(thickness 0.1524)
				)
			)
		)
		(property "Device Type" "PREFIT-150P-234294H542"
			(at -11.7475 -23.012654 0)
			(unlocked yes)
			(layer "F.Fab")
			(hide yes)
			(effects
				(font
					(size 1.016 1.016)
					(thickness 0.1524)
				)
			)
		)
		(duplicate_pad_numbers_are_jumpers no)
		(pad "G2" thru_hole circle
			(at 1.800098 -9.59993)
			(size 0.762 0.762)
			(drill 0.359918)
			(layers "*.Cu" "*.Mask")
			(remove_unused_layers no)
			(net "PCIE_SCC_B_TO_COMP_B_1_DP")
			(clearance 0.1651)
			(thermal_gap 0.1651)
		)
		(pad "G3" thru_hole circle
			(at 3.599942 -10.80008)
			(size 0.762 0.762)
			(drill 0.359918)
			(layers "*.Cu" "*.Mask")
			(remove_unused_layers no)
			(net "PCIE_SCC_B_TO_COMP_B_2_DP")
			(clearance 0.1651)
			(thermal_gap 0.1651)
		)
		(pad "G4" thru_hole circle
			(at 5.40004 -9.59993)
			(size 0.762 0.762)
			(drill 0.359918)
			(layers "*.Cu" "*.Mask")
			(remove_unused_layers no)
			(net "PCIE_SCC_B_TO_COMP_B_3_DP")
			(clearance 0.1651)
			(thermal_gap 0.1651)
		)
		(pad "G5" thru_hole circle
			(at 7.199884 -10.80008)
			(size 0.762 0.762)
			(drill 0.359918)
			(layers "*.Cu" "*.Mask")
			(remove_unused_layers no)
			(net "PCIE_SCC_B_TO_COMP_B_4_DP")
			(clearance 0.1651)
			(thermal_gap 0.1651)
		)
		(pad "G6" thru_hole circle
			(at 8.999982 -9.59993)
			(size 0.762 0.762)
			(drill 0.359918)
			(layers "*.Cu" "*.Mask")
			(remove_unused_layers no)
			(net "PCIE_SCC_B_TO_COMP_B_5_DP")
			(clearance 0.1651)
			(thermal_gap 0.1651)
		)
		(pad "G7" thru_hole circle
			(at 10.80008 -10.80008)
			(size 0.762 0.762)
			(drill 0.359918)
			(layers "*.Cu" "*.Mask")
			(remove_unused_layers no)
			(net "PCIE_SCC_B_TO_COMP_B_6_DP")
			(clearance 0.1651)
			(thermal_gap 0.1651)
		)
		(pad "G8" thru_hole circle
			(at 12.599924 -9.59993)
			(size 0.762 0.762)
			(drill 0.359918)
			(layers "*.Cu" "*.Mask")
			(remove_unused_layers no)
			(net "PCIE_SCC_B_TO_COMP_B_7_DP")
			(clearance 0.1651)
			(thermal_gap 0.1651)
		)
		(pad "G9" thru_hole circle
			(at 16.20012 -7.199884)
			(size 0.762 0.762)
			(drill 0.359918)
			(layers "*.Cu" "*.Mask")
			(remove_unused_layers no)
			(net "P12V_B_PGOOD")
			(clearance 0.1651)
			(thermal_gap 0.1651)
		)
		(pad "G10" thru_hole circle
			(at 17.999964 -4.899914)
			(size 0.762 0.762)
			(drill 0.359918)
			(layers "*.Cu" "*.Mask")
			(remove_unused_layers no)
			(net "IOM_B_INS_N")
			(clearance 0.1651)
			(thermal_gap 0.1651)
		)
		(pad "G11" thru_hole circle
			(at 19.800062 -7.199884)
			(size 0.762 0.762)
			(drill 0.359918)
			(layers "*.Cu" "*.Mask")
			(remove_unused_layers no)
			(net "DRIVE_B_30_ACT")
			(clearance 0.1651)
			(thermal_gap 0.1651)
		)
		(pad "G12" thru_hole circle
			(at 21.599906 -4.899914)
			(size 0.762 0.762)
			(drill 0.359918)
			(layers "*.Cu" "*.Mask")
			(remove_unused_layers no)
			(net "FDPB_FAN_LED0")
			(clearance 0.1651)
			(thermal_gap 0.1651)
		)
		(pad "GND1" thru_hole circle
			(at 0 -2.500122)
			(size 0.762 0.762)
			(drill 0.359918)
			(layers "*.Cu" "*.Mask")
			(remove_unused_layers no)
			(net "GND")
			(clearance 0.1651)
			(thermal_gap 0.1651)
		)
		(pad "GND2" thru_hole circle
			(at 0 -6.100064)
			(size 0.762 0.762)
			(drill 0.359918)
			(layers "*.Cu" "*.Mask")
			(remove_unused_layers no)
			(net "GND")
			(clearance 0.1651)
			(thermal_gap 0.1651)
		)
		(pad "GND3" thru_hole circle
			(at 0 -9.700006)
			(size 0.762 0.762)
			(drill 0.359918)
			(layers "*.Cu" "*.Mask")
			(remove_unused_layers no)
			(net "GND")
			(clearance 0.1651)
			(thermal_gap 0.1651)
		)
		(pad "GND4" thru_hole circle
			(at 0 -13.299948)
			(size 0.762 0.762)
			(drill 0.359918)
			(layers "*.Cu" "*.Mask")
			(remove_unused_layers no)
			(net "GND")
			(clearance 0.1651)
			(thermal_gap 0.1651)
		)
		(pad "GND5" thru_hole circle
			(at 1.800098 2.29997)
			(size 0.762 0.762)
			(drill 0.359918)
			(layers "*.Cu" "*.Mask")
			(remove_unused_layers no)
			(net "GND")
			(clearance 0.1651)
			(thermal_gap 0.1651)
		)
		(pad "GND6" thru_hole circle
			(at 1.800098 -1.299972)
			(size 0.762 0.762)
			(drill 0.359918)
			(layers "*.Cu" "*.Mask")
			(remove_unused_layers no)
			(net "GND")
			(clearance 0.1651)
			(thermal_gap 0.1651)
		)
		(pad "GND7" thru_hole circle
			(at 1.800098 -4.899914)
			(size 0.762 0.762)
			(drill 0.359918)
			(layers "*.Cu" "*.Mask")
			(remove_unused_layers no)
			(net "GND")
			(clearance 0.1651)
			(thermal_gap 0.1651)
		)
		(pad "GND8" thru_hole circle
			(at 1.800098 -8.50011)
			(size 0.762 0.762)
			(drill 0.359918)
			(layers "*.Cu" "*.Mask")
			(remove_unused_layers no)
			(net "GND")
			(clearance 0.1651)
			(thermal_gap 0.1651)
		)
		(pad "GND9" thru_hole circle
			(at 1.800098 -12.100052)
			(size 0.762 0.762)
			(drill 0.359918)
			(layers "*.Cu" "*.Mask")
			(remove_unused_layers no)
			(net "GND")
			(clearance 0.1651)
			(thermal_gap 0.1651)
		)
		(pad "GND10" thru_hole circle
			(at 3.599942 -2.500122)
			(size 0.762 0.762)
			(drill 0.359918)
			(layers "*.Cu" "*.Mask")
			(remove_unused_layers no)
			(net "GND")
			(clearance 0.1651)
			(thermal_gap 0.1651)
		)
		(pad "GND11" thru_hole circle
			(at 3.599942 -6.100064)
			(size 0.762 0.762)
			(drill 0.359918)
			(layers "*.Cu" "*.Mask")
			(remove_unused_layers no)
			(net "GND")
			(clearance 0.1651)
			(thermal_gap 0.1651)
		)
		(pad "GND12" thru_hole circle
			(at 3.599942 -9.700006)
			(size 0.762 0.762)
			(drill 0.359918)
			(layers "*.Cu" "*.Mask")
			(remove_unused_layers no)
			(net "GND")
			(clearance 0.1651)
			(thermal_gap 0.1651)
		)
		(pad "GND13" thru_hole circle
			(at 3.599942 -13.299948)
			(size 0.762 0.762)
			(drill 0.359918)
			(layers "*.Cu" "*.Mask")
			(remove_unused_layers no)
			(net "GND")
			(clearance 0.1651)
			(thermal_gap 0.1651)
		)
		(pad "GND14" thru_hole circle
			(at 5.40004 2.29997)
			(size 0.762 0.762)
			(drill 0.359918)
			(layers "*.Cu" "*.Mask")
			(remove_unused_layers no)
			(net "GND")
			(clearance 0.1651)
			(thermal_gap 0.1651)
		)
		(pad "GND15" thru_hole circle
			(at 5.40004 -1.299972)
			(size 0.762 0.762)
			(drill 0.359918)
			(layers "*.Cu" "*.Mask")
			(remove_unused_layers no)
			(net "GND")
			(clearance 0.1651)
			(thermal_gap 0.1651)
		)
		(pad "GND16" thru_hole circle
			(at 5.40004 -4.899914)
			(size 0.762 0.762)
			(drill 0.359918)
			(layers "*.Cu" "*.Mask")
			(remove_unused_layers no)
			(net "GND")
			(clearance 0.1651)
			(thermal_gap 0.1651)
		)
		(pad "GND17" thru_hole circle
			(at 5.40004 -8.50011)
			(size 0.762 0.762)
			(drill 0.359918)
			(layers "*.Cu" "*.Mask")
			(remove_unused_layers no)
			(net "GND")
			(clearance 0.1651)
			(thermal_gap 0.1651)
		)
		(pad "GND18" thru_hole circle
			(at 5.40004 -12.100052)
			(size 0.762 0.762)
			(drill 0.359918)
			(layers "*.Cu" "*.Mask")
			(remove_unused_layers no)
			(net "GND")
			(clearance 0.1651)
			(thermal_gap 0.1651)
		)
		(pad "GND19" thru_hole circle
			(at 7.199884 -2.500122)
			(size 0.762 0.762)
			(drill 0.359918)
			(layers "*.Cu" "*.Mask")
			(remove_unused_layers no)
			(net "GND")
			(clearance 0.1651)
			(thermal_gap 0.1651)
		)
		(pad "GND20" thru_hole circle
			(at 7.199884 -6.100064)
			(size 0.762 0.762)
			(drill 0.359918)
			(layers "*.Cu" "*.Mask")
			(remove_unused_layers no)
			(net "GND")
			(clearance 0.1651)
			(thermal_gap 0.1651)
		)
		(pad "GND21" thru_hole circle
			(at 7.199884 -9.700006)
			(size 0.762 0.762)
			(drill 0.359918)
			(layers "*.Cu" "*.Mask")
			(remove_unused_layers no)
			(net "GND")
			(clearance 0.1651)
			(thermal_gap 0.1651)
		)
		(pad "GND22" thru_hole circle
			(at 7.199884 -13.299948)
			(size 0.762 0.762)
			(drill 0.359918)
			(layers "*.Cu" "*.Mask")
			(remove_unused_layers no)
			(net "GND")
			(clearance 0.1651)
			(thermal_gap 0.1651)
		)
		(pad "GND23" thru_hole circle
			(at 8.999982 2.29997)
			(size 0.762 0.762)
			(drill 0.359918)
			(layers "*.Cu" "*.Mask")
			(remove_unused_layers no)
			(net "GND")
			(clearance 0.1651)
			(thermal_gap 0.1651)
		)
		(pad "GND24" thru_hole circle
			(at 8.999982 -1.299972)
			(size 0.762 0.762)
			(drill 0.359918)
			(layers "*.Cu" "*.Mask")
			(remove_unused_layers no)
			(net "GND")
			(clearance 0.1651)
			(thermal_gap 0.1651)
		)
		(pad "GND25" thru_hole circle
			(at 8.999982 -4.899914)
			(size 0.762 0.762)
			(drill 0.359918)
			(layers "*.Cu" "*.Mask")
			(remove_unused_layers no)
			(net "GND")
			(clearance 0.1651)
			(thermal_gap 0.1651)
		)
		(pad "GND26" thru_hole circle
			(at 8.999982 -8.50011)
			(size 0.762 0.762)
			(drill 0.359918)
			(layers "*.Cu" "*.Mask")
			(remove_unused_layers no)
			(net "GND")
			(clearance 0.1651)
			(thermal_gap 0.1651)
		)
		(pad "GND27" thru_hole circle
			(at 8.999982 -12.100052)
			(size 0.762 0.762)
			(drill 0.359918)
			(layers "*.Cu" "*.Mask")
			(remove_unused_layers no)
			(net "GND")
			(clearance 0.1651)
			(thermal_gap 0.1651)
		)
		(pad "GND28" thru_hole circle
			(at 10.80008 -2.500122)
			(size 0.762 0.762)
			(drill 0.359918)
			(layers "*.Cu" "*.Mask")
			(remove_unused_layers no)
			(net "GND")
			(clearance 0.1651)
			(thermal_gap 0.1651)
		)
		(pad "GND29" thru_hole circle
			(at 10.80008 -6.100064)
			(size 0.762 0.762)
			(drill 0.359918)
			(layers "*.Cu" "*.Mask")
			(remove_unused_layers no)
			(net "GND")
			(clearance 0.1651)
			(thermal_gap 0.1651)
		)
		(pad "GND30" thru_hole circle
			(at 10.80008 -9.700006)
			(size 0.762 0.762)
			(drill 0.359918)
			(layers "*.Cu" "*.Mask")
			(remove_unused_layers no)
			(net "GND")
			(clearance 0.1651)
			(thermal_gap 0.1651)
		)
		(pad "GND31" thru_hole circle
			(at 10.80008 -13.299948)
			(size 0.762 0.762)
			(drill 0.359918)
			(layers "*.Cu" "*.Mask")
			(remove_unused_layers no)
			(net "GND")
			(clearance 0.1651)
			(thermal_gap 0.1651)
		)
		(pad "GND32" thru_hole circle
			(at 12.599924 2.29997)
			(size 0.762 0.762)
			(drill 0.359918)
			(layers "*.Cu" "*.Mask")
			(remove_unused_layers no)
			(net "GND")
			(clearance 0.1651)
			(thermal_gap 0.1651)
		)
		(pad "GND33" thru_hole circle
			(at 12.599924 -1.299972)
			(size 0.762 0.762)
			(drill 0.359918)
			(layers "*.Cu" "*.Mask")
			(remove_unused_layers no)
			(net "GND")
			(clearance 0.1651)
			(thermal_gap 0.1651)
		)
		(pad "GND34" thru_hole circle
			(at 12.599924 -4.899914)
			(size 0.762 0.762)
			(drill 0.359918)
			(layers "*.Cu" "*.Mask")
			(remove_unused_layers no)
			(net "GND")
			(clearance 0.1651)
			(thermal_gap 0.1651)
		)
		(pad "GND35" thru_hole circle
			(at 12.599924 -8.50011)
			(size 0.762 0.762)
			(drill 0.359918)
			(layers "*.Cu" "*.Mask")
			(remove_unused_layers no)
			(net "GND")
			(clearance 0.1651)
			(thermal_gap 0.1651)
		)
		(pad "GND36" thru_hole circle
			(at 12.599924 -12.100052)
			(size 0.762 0.762)
			(drill 0.359918)
			(layers "*.Cu" "*.Mask")
			(remove_unused_layers no)
			(net "GND")
			(clearance 0.1651)
			(thermal_gap 0.1651)
		)
		(pad "H1" thru_hole circle
			(at 0 -12.199874)
			(size 0.762 0.762)
			(drill 0.359918)
			(layers "*.Cu" "*.Mask")
			(remove_unused_layers no)
			(net "PCIE_SCC_B_TO_COMP_B_0_DN")
			(clearance 0.1651)
			(thermal_gap 0.1651)
		)
		(pad "H2" thru_hole circle
			(at 1.800098 -10.999978)
			(size 0.762 0.762)
			(drill 0.359918)
			(layers "*.Cu" "*.Mask")
			(remove_unused_layers no)
			(net "PCIE_SCC_B_TO_COMP_B_1_DN")
			(clearance 0.1651)
			(thermal_gap 0.1651)
		)
		(pad "H3" thru_hole circle
			(at 3.599942 -12.199874)
			(size 0.762 0.762)
			(drill 0.359918)
			(layers "*.Cu" "*.Mask")
			(remove_unused_layers no)
			(net "PCIE_SCC_B_TO_COMP_B_2_DN")
			(clearance 0.1651)
			(thermal_gap 0.1651)
		)
		(pad "H4" thru_hole circle
			(at 5.40004 -10.999978)
			(size 0.762 0.762)
			(drill 0.359918)
			(layers "*.Cu" "*.Mask")
			(remove_unused_layers no)
			(net "PCIE_SCC_B_TO_COMP_B_3_DN")
			(clearance 0.1651)
			(thermal_gap 0.1651)
		)
		(pad "H5" thru_hole circle
			(at 7.199884 -12.199874)
			(size 0.762 0.762)
			(drill 0.359918)
			(layers "*.Cu" "*.Mask")
			(remove_unused_layers no)
			(net "PCIE_SCC_B_TO_COMP_B_4_DN")
			(clearance 0.1651)
			(thermal_gap 0.1651)
		)
		(pad "H6" thru_hole circle
			(at 8.999982 -10.999978)
			(size 0.762 0.762)
			(drill 0.359918)
			(layers "*.Cu" "*.Mask")
			(remove_unused_layers no)
			(net "PCIE_SCC_B_TO_COMP_B_5_DN")
			(clearance 0.1651)
			(thermal_gap 0.1651)
		)
		(pad "H7" thru_hole circle
			(at 10.80008 -12.199874)
			(size 0.762 0.762)
			(drill 0.359918)
			(layers "*.Cu" "*.Mask")
			(remove_unused_layers no)
			(net "PCIE_SCC_B_TO_COMP_B_6_DN")
			(clearance 0.1651)
			(thermal_gap 0.1651)
		)
		(pad "H8" thru_hole circle
			(at 12.599924 -10.999978)
			(size 0.762 0.762)
			(drill 0.359918)
			(layers "*.Cu" "*.Mask")
			(remove_unused_layers no)
			(net "PCIE_SCC_B_TO_COMP_B_7_DN")
			(clearance 0.1651)
			(thermal_gap 0.1651)
		)
		(pad "H9" thru_hole circle
			(at 16.20012 -8.599932)
			(size 0.762 0.762)
			(drill 0.359918)
			(layers "*.Cu" "*.Mask")
			(remove_unused_layers no)
			(net "SCC_B_STBY_PWR_EN")
			(clearance 0.1651)
			(thermal_gap 0.1651)
		)
		(pad "H10" thru_hole circle
			(at 17.999964 -5.999988)
			(size 0.762 0.762)
			(drill 0.359918)
			(layers "*.Cu" "*.Mask")
			(remove_unused_layers no)
			(net "SCC_A_INS_N")
			(clearance 0.1651)
			(thermal_gap 0.1651)
		)
		(pad "H11" thru_hole circle
			(at 19.800062 -8.599932)
			(size 0.762 0.762)
			(drill 0.359918)
			(layers "*.Cu" "*.Mask")
			(remove_unused_layers no)
			(net "DRIVE_B_31_ACT")
			(clearance 0.1651)
			(thermal_gap 0.1651)
		)
		(pad "H12" thru_hole circle
			(at 21.599906 -5.999988)
			(size 0.762 0.762)
			(drill 0.359918)
			(layers "*.Cu" "*.Mask")
			(remove_unused_layers no)
			(net "FDPB_FAN_LED1")
			(clearance 0.1651)
			(thermal_gap 0.1651)
		)
		(pad "J9" thru_hole circle
			(at 16.20012 -9.700006)
			(size 0.762 0.762)
			(drill 0.359918)
			(layers "*.Cu" "*.Mask")
			(remove_unused_layers no)
			(net "DPB_PWR_BTN_BUF_B")
			(clearance 0.1651)
			(thermal_gap 0.1651)
		)
		(pad "J10" thru_hole circle
			(at 17.999964 -7.400036)
			(size 0.762 0.762)
			(drill 0.359918)
			(layers "*.Cu" "*.Mask")
			(remove_unused_layers no)
			(net "SCC_B_INS_N")
			(clearance 0.1651)
			(thermal_gap 0.1651)
		)
		(pad "J11" thru_hole circle
			(at 19.800062 -9.700006)
			(size 0.762 0.762)
			(drill 0.359918)
			(layers "*.Cu" "*.Mask")
			(remove_unused_layers no)
			(net "DRIVE_B_32_ACT")
			(clearance 0.1651)
			(thermal_gap 0.1651)
		)
		(pad "J12" thru_hole circle
			(at 21.599906 -7.400036)
			(size 0.762 0.762)
			(drill 0.359918)
			(layers "*.Cu" "*.Mask")
			(remove_unused_layers no)
			(net "FDPB_FAN_LED2")
			(clearance 0.1651)
			(thermal_gap 0.1651)
		)
		(pad "K9" thru_hole circle
			(at 16.20012 -10.80008)
			(size 0.762 0.762)
			(drill 0.359918)
			(layers "*.Cu" "*.Mask")
			(remove_unused_layers no)
			(net "SCC_B_FAULT_LED")
			(clearance 0.1651)
			(thermal_gap 0.1651)
		)
		(pad "K10" thru_hole circle
			(at 17.999964 -8.50011)
			(size 0.762 0.762)
			(drill 0.359918)
			(layers "*.Cu" "*.Mask")
			(remove_unused_layers no)
			(net "SCC_B_TYPE_0")
			(clearance 0.1651)
			(thermal_gap 0.1651)
		)
		(pad "K11" thru_hole circle
			(at 19.800062 -10.80008)
			(size 0.762 0.762)
			(drill 0.359918)
			(layers "*.Cu" "*.Mask")
			(remove_unused_layers no)
			(net "DRIVE_B_33_ACT")
			(clearance 0.1651)
			(thermal_gap 0.1651)
		)
		(pad "K12" thru_hole circle
			(at 21.599906 -8.50011)
			(size 0.762 0.762)
			(drill 0.359918)
			(layers "*.Cu" "*.Mask")
			(remove_unused_layers no)
			(net "FDPB_FAN_LED3")
			(clearance 0.1651)
			(thermal_gap 0.1651)
		)
		(pad "L9" thru_hole circle
			(at 16.20012 -12.199874)
			(size 0.762 0.762)
			(drill 0.359918)
			(layers "*.Cu" "*.Mask")
			(remove_unused_layers no)
			(net "SCC_B_TYPE_3")
			(clearance 0.1651)
			(thermal_gap 0.1651)
		)
		(pad "L10" thru_hole circle
			(at 17.999964 -9.59993)
			(size 0.762 0.762)
			(drill 0.359918)
			(layers "*.Cu" "*.Mask")
			(remove_unused_layers no)
			(net "SCC_B_TYPE_1")
			(clearance 0.1651)
			(thermal_gap 0.1651)
		)
		(pad "L11" thru_hole circle
			(at 19.800062 -12.199874)
			(size 0.762 0.762)
			(drill 0.359918)
			(layers "*.Cu" "*.Mask")
			(remove_unused_layers no)
			(net "DRIVE_B_34_ACT")
			(clearance 0.1651)
			(thermal_gap 0.1651)
		)
		(pad "L12" thru_hole circle
			(at 21.599906 -9.59993)
			(size 0.762 0.762)
			(drill 0.359918)
			(layers "*.Cu" "*.Mask")
			(remove_unused_layers no)
			(net "P3V3_STBY_A")
			(clearance 0.1651)
			(thermal_gap 0.1651)
		)
		(pad "M9" thru_hole circle
			(at 16.20012 -13.299948)
			(size 0.762 0.762)
			(drill 0.359918)
			(layers "*.Cu" "*.Mask")
			(remove_unused_layers no)
			(net "GND")
			(clearance 0.1651)
			(thermal_gap 0.1651)
		)
		(pad "M10" thru_hole circle
			(at 17.999964 -10.999978)
			(size 0.762 0.762)
			(drill 0.359918)
			(layers "*.Cu" "*.Mask")
			(remove_unused_layers no)
			(net "SCC_B_TYPE_2")
			(clearance 0.1651)
			(thermal_gap 0.1651)
		)
		(pad "M11" thru_hole circle
			(at 19.800062 -13.299948)
			(size 0.762 0.762)
			(drill 0.359918)
			(layers "*.Cu" "*.Mask")
			(remove_unused_layers no)
			(net "DRIVE_B_35_ACT")
			(clearance 0.1651)
			(thermal_gap 0.1651)
		)
		(pad "M12" thru_hole circle
			(at 21.599906 -10.999978)
			(size 0.762 0.762)
			(drill 0.359918)
			(layers "*.Cu" "*.Mask")
			(remove_unused_layers no)
			(net "P3V3_STBY_B")
			(clearance 0.1651)
			(thermal_gap 0.1651)
		)
		(pad "N10" thru_hole circle
			(at 17.999964 -12.100052)
			(size 0.762 0.762)
			(drill 0.359918)
			(layers "*.Cu" "*.Mask")
			(remove_unused_layers no)
			(net "GND")
			(clearance 0.1651)
			(thermal_gap 0.1651)
		)
		(pad "N12" thru_hole circle
			(at 21.599906 -12.100052)
			(size 0.762 0.762)
			(drill 0.359918)
			(layers "*.Cu" "*.Mask")
			(remove_unused_layers no)
			(net "P5V_B_2")
			(clearance 0.1651)
			(thermal_gap 0.1651)
		)
	)
)
